# SCM (Grand Teton) — schematic netlist excerpt (pin names and nets, part order shuffled) for the footprints in the layout excerpt that follows; sources: Cadence DE-HDL packaged netlist, KiCad conversion of 12092022_DA0F0TMDCD0_F0T_Management_Board_D_brd_V3_OCP.brd

C30  Q_CAP  1UF 25V 10% X6S  pkg C0402  page 13 : A = P3V3_P2V5_P1V8_RVDD ; B = GND
R887  Q_RES  4.7K 1% EMPTY  pkg 0402LF  page 22 : A = P3V3_AUX ; B = RST_BMC_HW

(kicad_pcb
	(version 20260206)
	(generator "pcbnew")
	(generator_version "10.0")
	(general
		(thickness 1.6)
		(legacy_teardrops no)
	)
	(paper "A4")
	(title_block
		(title "12092022_DA0F0TMDCD0_F0T_Management_Board_D_brd_V3_OCP.brd")
		(comment 1 "Grand Teton / footprints 611-612 of 1440")
	)
	(layers
		(0 "F.Cu" signal "TOP")
		(4 "In1.Cu" signal "GND")
		(6 "In2.Cu" signal "IN1")
		(8 "In3.Cu" signal "GND1")
		(10 "In4.Cu" signal "IN2")
		(12 "In5.Cu" signal "VCC")
		(14 "In6.Cu" signal "VCC1")
		(16 "In7.Cu" signal "IN3")
		(18 "In8.Cu" signal "GND2")
		(20 "In9.Cu" signal "IN4")
		(22 "In10.Cu" signal "GND3")
		(2 "B.Cu" signal "BOTTOM")
		(9 "F.Adhes" user "F.Adhesive")
		(11 "B.Adhes" user "B.Adhesive")
		(13 "F.Paste" user "Package Geometry/Pastemask Top")
		(15 "B.Paste" user "Package Geometry/Pastemask Bottom")
		(5 "F.SilkS" user "Ref Des/Silkscreen Top")
		(7 "B.SilkS" user "Ref Des/Silkscreen Bottom")
		(1 "F.Mask" user "Board Geometry/Soldermask Top")
		(3 "B.Mask" user "Board Geometry/Soldermask Bottom")
		(17 "Dwgs.User" user "User.Drawings")
		(19 "Cmts.User" user "User.Comments")
		(21 "Eco1.User" user "User.Eco1")
		(23 "Eco2.User" user "User.Eco2")
		(25 "Edge.Cuts" user "Board Geometry/Outline")
		(27 "Margin" user)
		(31 "F.CrtYd" user "Package Geometry/Place Bound Top")
		(29 "B.CrtYd" user "Package Geometry/Place Bound Bottom")
		(35 "F.Fab" user "Ref Des/Assembly Top")
		(33 "B.Fab" user "Ref Des/Assembly Bottom")
	)
	(footprint ""
		(layer "F.Cu")
		(at 10.287 -96.393 90)
		(property "Reference" "R887"
			(at 0 0 90)
			(layer "F.SilkS")
			(hide yes)
			(effects
				(font
					(size 1.27 1.27)
				)
			)
		)
		(property "Value" ""
			(at 0 0 90)
			(layer "F.Fab")
			(effects
				(font
					(size 1.27 1.27)
				)
			)
		)
		(duplicate_pad_numbers_are_jumpers no)
		(fp_line
			(start 0.7874 -0.4064)
			(end 0.7874 0.4064)
			(stroke
				(width 0.1524)
				(type default)
			)
			(layer "F.SilkS")
		)
		(fp_line
			(start -0.7874 -0.4064)
			(end 0.7874 -0.4064)
			(stroke
				(width 0.1524)
				(type default)
			)
			(layer "F.SilkS")
		)
		(fp_line
			(start 0.7874 0.4064)
			(end -0.7874 0.4064)
			(stroke
				(width 0.1524)
				(type default)
			)
			(layer "F.SilkS")
		)
		(fp_line
			(start -0.7874 0.4064)
			(end -0.7874 -0.4064)
			(stroke
				(width 0.1524)
				(type default)
			)
			(layer "F.SilkS")
		)
		(fp_line
			(start -0.12065 -0.305054)
			(end -0.12065 -0.2794)
			(stroke
				(width 0.1)
				(type default)
			)
			(layer "F.Fab")
		)
		(fp_line
			(start -0.67945 -0.305054)
			(end -0.12065 -0.305054)
			(stroke
				(width 0.1)
				(type default)
			)
			(layer "F.Fab")
		)
		(fp_line
			(start 0.67945 -0.3048)
			(end 0.67945 0.3048)
			(stroke
				(width 0.1)
				(type default)
			)
			(layer "F.Fab")
		)
		(fp_line
			(start 0.12065 -0.3048)
			(end 0.67945 -0.3048)
			(stroke
				(width 0.1)
				(type default)
			)
			(layer "F.Fab")
		)
		(fp_line
			(start 0.12065 -0.2794)
			(end 0.12065 -0.3048)
			(stroke
				(width 0.1)
				(type default)
			)
			(layer "F.Fab")
		)
		(fp_line
			(start -0.12065 -0.2794)
			(end 0.12065 -0.2794)
			(stroke
				(width 0.1)
				(type default)
			)
			(layer "F.Fab")
		)
		(fp_line
			(start 0.120396 0.2794)
			(end -0.12065 0.2794)
			(stroke
				(width 0.1)
				(type default)
			)
			(layer "F.Fab")
		)
		(fp_line
			(start -0.12065 0.2794)
			(end -0.12065 0.3048)
			(stroke
				(width 0.1)
				(type default)
			)
			(layer "F.Fab")
		)
		(fp_line
			(start 0.67945 0.3048)
			(end 0.120396 0.3048)
			(stroke
				(width 0.1)
				(type default)
			)
			(layer "F.Fab")
		)
		(fp_line
			(start 0.120396 0.3048)
			(end 0.120396 0.2794)
			(stroke
				(width 0.1)
				(type default)
			)
			(layer "F.Fab")
		)
		(fp_line
			(start -0.12065 0.3048)
			(end -0.67945 0.3048)
			(stroke
				(width 0.1)
				(type default)
			)
			(layer "F.Fab")
		)
		(fp_line
			(start -0.67945 0.3048)
			(end -0.67945 -0.305054)
			(stroke
				(width 0.1)
				(type default)
			)
			(layer "F.Fab")
		)
		(pad "1" smd circle
			(at -0.40005 0 90)
			(size 0 0)
			(layers "F.Cu" "F.Mask" "F.Paste")
			(net "P3V3_AUX")
		)
		(pad "2" smd circle
			(at 0.40005 0 90)
			(size 0 0)
			(layers "F.Cu" "F.Mask" "F.Paste")
			(net "RST_BMC_HW")
		)
	)
	(footprint ""
		(layer "F.Cu")
		(at 38.718236 -38.53561 90)
		(property "Reference" "C30"
			(at 0 0 90)
			(layer "F.SilkS")
			(hide yes)
			(effects
				(font
					(size 1.27 1.27)
				)
			)
		)
		(property "Value" ""
			(at 0 0 90)
			(layer "F.Fab")
			(effects
				(font
					(size 1.27 1.27)
				)
			)
		)
		(duplicate_pad_numbers_are_jumpers no)
		(fp_line
			(start 0.7874 -0.4064)
			(end 0.7874 0.4064)
			(stroke
				(width 0.1524)
				(type default)
			)
			(layer "F.SilkS")
		)
		(fp_line
			(start -0.7874 -0.4064)
			(end 0.7874 -0.4064)
			(stroke
				(width 0.1524)
				(type default)
			)
			(layer "F.SilkS")
		)
		(fp_line
			(start 0.7874 0.4064)
			(end -0.7874 0.4064)
			(stroke
				(width 0.1524)
				(type default)
			)
			(layer "F.SilkS")
		)
		(fp_line
			(start -0.7874 0.4064)
			(end -0.7874 -0.4064)
			(stroke
				(width 0.1524)
				(type default)
			)
			(layer "F.SilkS")
		)
		(fp_line
			(start -0.12065 -0.305054)
			(end -0.12065 -0.2794)
			(stroke
				(width 0.1)
				(type default)
			)
			(layer "F.Fab")
		)
		(fp_line
			(start -0.67945 -0.305054)
			(end -0.12065 -0.305054)
			(stroke
				(width 0.1)
				(type default)
			)
			(layer "F.Fab")
		)
		(fp_line
			(start 0.67945 -0.3048)
			(end 0.67945 0.3048)
			(stroke
				(width 0.1)
				(type default)
			)
			(layer "F.Fab")
		)
		(fp_line
			(start 0.12065 -0.3048)
			(end 0.67945 -0.3048)
			(stroke
				(width 0.1)
				(type default)
			)
			(layer "F.Fab")
		)
		(fp_line
			(start 0.12065 -0.2794)
			(end 0.12065 -0.3048)
			(stroke
				(width 0.1)
				(type default)
			)
			(layer "F.Fab")
		)
		(fp_line
			(start -0.12065 -0.2794)
			(end 0.12065 -0.2794)
			(stroke
				(width 0.1)
				(type default)
			)
			(layer "F.Fab")
		)
		(fp_line
			(start 0.120396 0.2794)
			(end -0.12065 0.2794)
			(stroke
				(width 0.1)
				(type default)
			)
			(layer "F.Fab")
		)
		(fp_line
			(start -0.12065 0.2794)
			(end -0.12065 0.3048)
			(stroke
				(width 0.1)
				(type default)
			)
			(layer "F.Fab")
		)
		(fp_line
			(start 0.67945 0.3048)
			(end 0.120396 0.3048)
			(stroke
				(width 0.1)
				(type default)
			)
			(layer "F.Fab")
		)
		(fp_line
			(start 0.120396 0.3048)
			(end 0.120396 0.2794)
			(stroke
				(width 0.1)
				(type default)
			)
			(layer "F.Fab")
		)
		(fp_line
			(start -0.12065 0.3048)
			(end -0.67945 0.3048)
			(stroke
				(width 0.1)
				(type default)
			)
			(layer "F.Fab")
		)
		(fp_line
			(start -0.67945 0.3048)
			(end -0.67945 -0.305054)
			(stroke
				(width 0.1)
				(type default)
			)
			(layer "F.Fab")
		)
		(pad "1" smd circle
			(at -0.40005 0 90)
			(size 0 0)
			(layers "F.Cu" "F.Mask" "F.Paste")
			(net "P3V3_P2V5_P1V8_RVDD")
		)
		(pad "2" smd circle
			(at 0.40005 0 90)
			(size 0 0)
			(layers "F.Cu" "F.Mask" "F.Paste")
			(net "GND")
		)
	)
)
